(kicad_pcb
	(version 20260206)
	(generator "pcbnew")
	(generator_version "10.0")
	(general
		(thickness 1.6)
		(legacy_teardrops no)
	)
	(paper "A4")
	(title_block
		(title "01162023_DA0F0TEBIF0_F0T_Expander_BD_F_brd_V02_OCP.brd")
		(comment 1 "Grand Teton / footprints 1956-1962 of 9728")
	)
	(layers
		(0 "F.Cu" signal "TOP")
		(4 "In1.Cu" signal "GND")
		(6 "In2.Cu" signal "VCC")
		(8 "In3.Cu" signal "VCC1")
		(10 "In4.Cu" signal "GND1")
		(12 "In5.Cu" signal "IN1")
		(14 "In6.Cu" signal "GND2")
		(16 "In7.Cu" signal "IN2")
		(18 "In8.Cu" signal "GND3")
		(20 "In9.Cu" signal "IN3")
		(22 "In10.Cu" signal "GND4")
		(24 "In11.Cu" signal "IN4")
		(26 "In12.Cu" signal "GND5")
		(28 "In13.Cu" signal "IN5")
		(30 "In14.Cu" signal "GND6")
		(32 "In15.Cu" signal "IN6")
		(34 "In16.Cu" signal "GND7")
		(2 "B.Cu" signal "BOTTOM")
		(9 "F.Adhes" user "F.Adhesive")
		(11 "B.Adhes" user "B.Adhesive")
		(13 "F.Paste" user "Package Geometry/Pastemask Top")
		(15 "B.Paste" user "Package Geometry/Pastemask Bottom")
		(5 "F.SilkS" user "Ref Des/Silkscreen Top")
		(7 "B.SilkS" user "Ref Des/Silkscreen Bottom")
		(1 "F.Mask" user "Board Geometry/Soldermask Top")
		(3 "B.Mask" user "Board Geometry/Soldermask Bottom")
		(17 "Dwgs.User" user "User.Drawings")
		(19 "Cmts.User" user "User.Comments")
		(21 "Eco1.User" user "User.Eco1")
		(23 "Eco2.User" user "User.Eco2")
		(25 "Edge.Cuts" user "Board Geometry/Outline")
		(27 "Margin" user)
		(31 "F.CrtYd" user "Package Geometry/Place Bound Top")
		(29 "B.CrtYd" user "Package Geometry/Place Bound Bottom")
		(35 "F.Fab" user "Ref Des/Assembly Top")
		(33 "B.Fab" user "Ref Des/Assembly Bottom")
	)
	(footprint ""
		(layer "F.Cu")
		(at 198.473822 -27.006296 -90)
		(property "Reference" "PC936"
			(at 0 0 270)
			(layer "F.SilkS")
			(hide yes)
			(effects
				(font
					(size 1.27 1.27)
				)
			)
		)
		(property "Value" ""
			(at 0 0 270)
			(layer "F.Fab")
			(effects
				(font
					(size 1.27 1.27)
				)
			)
		)
		(duplicate_pad_numbers_are_jumpers no)
		(fp_line
			(start -0.7874 0.4064)
			(end -0.7874 -0.4064)
			(stroke
				(width 0.1524)
				(type default)
			)
			(layer "F.SilkS")
		)
		(fp_line
			(start 0.7874 0.4064)
			(end -0.7874 0.4064)
			(stroke
				(width 0.1524)
				(type default)
			)
			(layer "F.SilkS")
		)
		(fp_line
			(start -0.7874 -0.4064)
			(end 0.7874 -0.4064)
			(stroke
				(width 0.1524)
				(type default)
			)
			(layer "F.SilkS")
		)
		(fp_line
			(start 0.7874 -0.4064)
			(end 0.7874 0.4064)
			(stroke
				(width 0.1524)
				(type default)
			)
			(layer "F.SilkS")
		)
		(fp_line
			(start -0.67945 0.3048)
			(end -0.67945 -0.305054)
			(stroke
				(width 0.1)
				(type default)
			)
			(layer "F.Fab")
		)
		(fp_line
			(start -0.12065 0.3048)
			(end -0.67945 0.3048)
			(stroke
				(width 0.1)
				(type default)
			)
			(layer "F.Fab")
		)
		(fp_line
			(start 0.120396 0.3048)
			(end 0.120396 0.2794)
			(stroke
				(width 0.1)
				(type default)
			)
			(layer "F.Fab")
		)
		(fp_line
			(start 0.67945 0.3048)
			(end 0.120396 0.3048)
			(stroke
				(width 0.1)
				(type default)
			)
			(layer "F.Fab")
		)
		(fp_line
			(start -0.12065 0.2794)
			(end -0.12065 0.3048)
			(stroke
				(width 0.1)
				(type default)
			)
			(layer "F.Fab")
		)
		(fp_line
			(start 0.120396 0.2794)
			(end -0.12065 0.2794)
			(stroke
				(width 0.1)
				(type default)
			)
			(layer "F.Fab")
		)
		(fp_line
			(start -0.12065 -0.2794)
			(end 0.12065 -0.2794)
			(stroke
				(width 0.1)
				(type default)
			)
			(layer "F.Fab")
		)
		(fp_line
			(start 0.12065 -0.2794)
			(end 0.12065 -0.3048)
			(stroke
				(width 0.1)
				(type default)
			)
			(layer "F.Fab")
		)
		(fp_line
			(start 0.12065 -0.3048)
			(end 0.67945 -0.3048)
			(stroke
				(width 0.1)
				(type default)
			)
			(layer "F.Fab")
		)
		(fp_line
			(start 0.67945 -0.3048)
			(end 0.67945 0.3048)
			(stroke
				(width 0.1)
				(type default)
			)
			(layer "F.Fab")
		)
		(fp_line
			(start -0.67945 -0.305054)
			(end -0.12065 -0.305054)
			(stroke
				(width 0.1)
				(type default)
			)
			(layer "F.Fab")
		)
		(fp_line
			(start -0.12065 -0.305054)
			(end -0.12065 -0.2794)
			(stroke
				(width 0.1)
				(type default)
			)
			(layer "F.Fab")
		)
		(pad "1" smd circle
			(at -0.40005 0 270)
			(size 0 0)
			(layers "F.Cu" "F.Mask" "F.Paste")
			(net "P3V3_SSD7_CO_MODE")
		)
		(pad "2" smd circle
			(at 0.40005 0 270)
			(size 0 0)
			(layers "F.Cu" "F.Mask" "F.Paste")
			(net "GND")
		)
	)
	(footprint ""
		(layer "F.Cu")
		(at 125.546612 -152.859994 180)
		(property "Reference" "PR6889"
			(at 0 0 180)
			(layer "F.SilkS")
			(hide yes)
			(effects
				(font
					(size 1.27 1.27)
				)
			)
		)
		(property "Value" ""
			(at 0 0 180)
			(layer "F.Fab")
			(effects
				(font
					(size 1.27 1.27)
				)
			)
		)
		(duplicate_pad_numbers_are_jumpers no)
		(fp_line
			(start 1.2954 0.5842)
			(end -1.2954 0.5842)
			(stroke
				(width 0.1524)
				(type default)
			)
			(layer "F.SilkS")
		)
		(fp_line
			(start 1.2954 -0.5842)
			(end 1.2954 0.5842)
			(stroke
				(width 0.1524)
				(type default)
			)
			(layer "F.SilkS")
		)
		(fp_line
			(start -1.2954 0.5842)
			(end -1.2954 -0.5842)
			(stroke
				(width 0.1524)
				(type default)
			)
			(layer "F.SilkS")
		)
		(fp_line
			(start -1.2954 -0.5842)
			(end 1.2954 -0.5842)
			(stroke
				(width 0.1524)
				(type default)
			)
			(layer "F.SilkS")
		)
		(fp_line
			(start 1.1938 0.4064)
			(end 0.8636 0.4064)
			(stroke
				(width 0.1)
				(type default)
			)
			(layer "F.Fab")
		)
		(fp_line
			(start 1.1938 -0.406654)
			(end 1.1938 0.4064)
			(stroke
				(width 0.1)
				(type default)
			)
			(layer "F.Fab")
		)
		(fp_line
			(start 0.8636 0.4572)
			(end -0.8636 0.4572)
			(stroke
				(width 0.1)
				(type default)
			)
			(layer "F.Fab")
		)
		(fp_line
			(start 0.8636 0.4064)
			(end 0.8636 0.4572)
			(stroke
				(width 0.1)
				(type default)
			)
			(layer "F.Fab")
		)
		(fp_line
			(start 0.8636 -0.406654)
			(end 1.1938 -0.406654)
			(stroke
				(width 0.1)
				(type default)
			)
			(layer "F.Fab")
		)
		(fp_line
			(start 0.8636 -0.4572)
			(end 0.8636 -0.406654)
			(stroke
				(width 0.1)
				(type default)
			)
			(layer "F.Fab")
		)
		(fp_line
			(start -0.8636 0.4572)
			(end -0.8636 0.4318)
			(stroke
				(width 0.1)
				(type default)
			)
			(layer "F.Fab")
		)
		(fp_line
			(start -0.8636 0.4318)
			(end -0.8636 0.4064)
			(stroke
				(width 0.1)
				(type default)
			)
			(layer "F.Fab")
		)
		(fp_line
			(start -0.8636 0.4064)
			(end -1.1938 0.4064)
			(stroke
				(width 0.1)
				(type default)
			)
			(layer "F.Fab")
		)
		(fp_line
			(start -0.8636 -0.406654)
			(end -0.8636 -0.4572)
			(stroke
				(width 0.1)
				(type default)
			)
			(layer "F.Fab")
		)
		(fp_line
			(start -0.8636 -0.4572)
			(end 0.8636 -0.4572)
			(stroke
				(width 0.1)
				(type default)
			)
			(layer "F.Fab")
		)
		(fp_line
			(start -1.1938 0.4064)
			(end -1.1938 -0.406654)
			(stroke
				(width 0.1)
				(type default)
			)
			(layer "F.Fab")
		)
		(fp_line
			(start -1.1938 -0.406654)
			(end -0.8636 -0.406654)
			(stroke
				(width 0.1)
				(type default)
			)
			(layer "F.Fab")
		)
		(pad "1" smd rect
			(at -0.7366 0 90)
			(size 0.7112 0.8128)
			(layers "F.Cu" "F.Mask" "F.Paste")
			(net "P12V_NIC2_CO_AVIN_PD")
		)
		(pad "2" smd rect
			(at 0.7366 0 90)
			(size 0.7112 0.8128)
			(layers "F.Cu" "F.Mask" "F.Paste")
			(net "P12V_AUX")
		)
	)
	(footprint ""
		(layer "F.Cu")
		(at 223.679512 -231.416606 -90)
		(property "Reference" "R4547"
			(at 0 0 270)
			(layer "F.SilkS")
			(hide yes)
			(effects
				(font
					(size 1.27 1.27)
				)
			)
		)
		(property "Value" ""
			(at 0 0 270)
			(layer "F.Fab")
			(effects
				(font
					(size 1.27 1.27)
				)
			)
		)
		(duplicate_pad_numbers_are_jumpers no)
		(fp_line
			(start -0.7874 0.4064)
			(end -0.7874 -0.4064)
			(stroke
				(width 0.1524)
				(type default)
			)
			(layer "F.SilkS")
		)
		(fp_line
			(start 0.7874 0.4064)
			(end -0.7874 0.4064)
			(stroke
				(width 0.1524)
				(type default)
			)
			(layer "F.SilkS")
		)
		(fp_line
			(start -0.7874 -0.4064)
			(end 0.7874 -0.4064)
			(stroke
				(width 0.1524)
				(type default)
			)
			(layer "F.SilkS")
		)
		(fp_line
			(start 0.7874 -0.4064)
			(end 0.7874 0.4064)
			(stroke
				(width 0.1524)
				(type default)
			)
			(layer "F.SilkS")
		)
		(fp_line
			(start -0.67945 0.3048)
			(end -0.67945 -0.305054)
			(stroke
				(width 0.1)
				(type default)
			)
			(layer "F.Fab")
		)
		(fp_line
			(start -0.12065 0.3048)
			(end -0.67945 0.3048)
			(stroke
				(width 0.1)
				(type default)
			)
			(layer "F.Fab")
		)
		(fp_line
			(start 0.120396 0.3048)
			(end 0.120396 0.2794)
			(stroke
				(width 0.1)
				(type default)
			)
			(layer "F.Fab")
		)
		(fp_line
			(start 0.67945 0.3048)
			(end 0.120396 0.3048)
			(stroke
				(width 0.1)
				(type default)
			)
			(layer "F.Fab")
		)
		(fp_line
			(start -0.12065 0.2794)
			(end -0.12065 0.3048)
			(stroke
				(width 0.1)
				(type default)
			)
			(layer "F.Fab")
		)
		(fp_line
			(start 0.120396 0.2794)
			(end -0.12065 0.2794)
			(stroke
				(width 0.1)
				(type default)
			)
			(layer "F.Fab")
		)
		(fp_line
			(start -0.12065 -0.2794)
			(end 0.12065 -0.2794)
			(stroke
				(width 0.1)
				(type default)
			)
			(layer "F.Fab")
		)
		(fp_line
			(start 0.12065 -0.2794)
			(end 0.12065 -0.3048)
			(stroke
				(width 0.1)
				(type default)
			)
			(layer "F.Fab")
		)
		(fp_line
			(start 0.12065 -0.3048)
			(end 0.67945 -0.3048)
			(stroke
				(width 0.1)
				(type default)
			)
			(layer "F.Fab")
		)
		(fp_line
			(start 0.67945 -0.3048)
			(end 0.67945 0.3048)
			(stroke
				(width 0.1)
				(type default)
			)
			(layer "F.Fab")
		)
		(fp_line
			(start -0.67945 -0.305054)
			(end -0.12065 -0.305054)
			(stroke
				(width 0.1)
				(type default)
			)
			(layer "F.Fab")
		)
		(fp_line
			(start -0.12065 -0.305054)
			(end -0.12065 -0.2794)
			(stroke
				(width 0.1)
				(type default)
			)
			(layer "F.Fab")
		)
		(pad "1" smd circle
			(at -0.40005 0 270)
			(size 0 0)
			(layers "F.Cu" "F.Mask" "F.Paste")
			(net "GND")
		)
		(pad "2" smd circle
			(at 0.40005 0 270)
			(size 0 0)
			(layers "F.Cu" "F.Mask" "F.Paste")
			(net "REV_ID0")
		)
	)
	(footprint ""
		(layer "F.Cu")
		(at 98.975672 -122.525028)
		(property "Reference" "PC348"
			(at 0 0 0)
			(layer "F.SilkS")
			(hide yes)
			(effects
				(font
					(size 1.27 1.27)
				)
			)
		)
		(property "Value" ""
			(at 0 0 0)
			(layer "F.Fab")
			(effects
				(font
					(size 1.27 1.27)
				)
			)
		)
		(duplicate_pad_numbers_are_jumpers no)
		(fp_line
			(start -0.7874 -0.4064)
			(end 0.7874 -0.4064)
			(stroke
				(width 0.1524)
				(type default)
			)
			(layer "F.SilkS")
		)
		(fp_line
			(start -0.7874 0.4064)
			(end -0.7874 -0.4064)
			(stroke
				(width 0.1524)
				(type default)
			)
			(layer "F.SilkS")
		)
		(fp_line
			(start 0.7874 -0.4064)
			(end 0.7874 0.4064)
			(stroke
				(width 0.1524)
				(type default)
			)
			(layer "F.SilkS")
		)
		(fp_line
			(start 0.7874 0.4064)
			(end -0.7874 0.4064)
			(stroke
				(width 0.1524)
				(type default)
			)
			(layer "F.SilkS")
		)
		(fp_line
			(start -0.67945 -0.305054)
			(end -0.12065 -0.305054)
			(stroke
				(width 0.1)
				(type default)
			)
			(layer "F.Fab")
		)
		(fp_line
			(start -0.67945 0.3048)
			(end -0.67945 -0.305054)
			(stroke
				(width 0.1)
				(type default)
			)
			(layer "F.Fab")
		)
		(fp_line
			(start -0.12065 -0.305054)
			(end -0.12065 -0.2794)
			(stroke
				(width 0.1)
				(type default)
			)
			(layer "F.Fab")
		)
		(fp_line
			(start -0.12065 -0.2794)
			(end 0.12065 -0.2794)
			(stroke
				(width 0.1)
				(type default)
			)
			(layer "F.Fab")
		)
		(fp_line
			(start -0.12065 0.2794)
			(end -0.12065 0.3048)
			(stroke
				(width 0.1)
				(type default)
			)
			(layer "F.Fab")
		)
		(fp_line
			(start -0.12065 0.3048)
			(end -0.67945 0.3048)
			(stroke
				(width 0.1)
				(type default)
			)
			(layer "F.Fab")
		)
		(fp_line
			(start 0.120396 0.2794)
			(end -0.12065 0.2794)
			(stroke
				(width 0.1)
				(type default)
			)
			(layer "F.Fab")
		)
		(fp_line
			(start 0.120396 0.3048)
			(end 0.120396 0.2794)
			(stroke
				(width 0.1)
				(type default)
			)
			(layer "F.Fab")
		)
		(fp_line
			(start 0.12065 -0.3048)
			(end 0.67945 -0.3048)
			(stroke
				(width 0.1)
				(type default)
			)
			(layer "F.Fab")
		)
		(fp_line
			(start 0.12065 -0.2794)
			(end 0.12065 -0.3048)
			(stroke
				(width 0.1)
				(type default)
			)
			(layer "F.Fab")
		)
		(fp_line
			(start 0.67945 -0.3048)
			(end 0.67945 0.3048)
			(stroke
				(width 0.1)
				(type default)
			)
			(layer "F.Fab")
		)
		(fp_line
			(start 0.67945 0.3048)
			(end 0.120396 0.3048)
			(stroke
				(width 0.1)
				(type default)
			)
			(layer "F.Fab")
		)
		(pad "1" smd circle
			(at -0.40005 0)
			(size 0 0)
			(layers "F.Cu" "F.Mask" "F.Paste")
			(net "P5V_AUX")
		)
		(pad "2" smd circle
			(at 0.40005 0)
			(size 0 0)
			(layers "F.Cu" "F.Mask" "F.Paste")
			(net "GND")
		)
	)
	(footprint ""
		(layer "F.Cu")
		(at 101.610922 -245.339616 -90)
		(property "Reference" "C831"
			(at 0 0 270)
			(layer "F.SilkS")
			(hide yes)
			(effects
				(font
					(size 1.27 1.27)
				)
			)
		)
		(property "Value" ""
			(at 0 0 270)
			(layer "F.Fab")
			(effects
				(font
					(size 1.27 1.27)
				)
			)
		)
		(duplicate_pad_numbers_are_jumpers no)
		(fp_line
			(start -0.7874 0.4064)
			(end -0.7874 -0.4064)
			(stroke
				(width 0.1524)
				(type default)
			)
			(layer "F.SilkS")
		)
		(fp_line
			(start 0.7874 0.4064)
			(end -0.7874 0.4064)
			(stroke
				(width 0.1524)
				(type default)
			)
			(layer "F.SilkS")
		)
		(fp_line
			(start -0.7874 -0.4064)
			(end 0.7874 -0.4064)
			(stroke
				(width 0.1524)
				(type default)
			)
			(layer "F.SilkS")
		)
		(fp_line
			(start 0.7874 -0.4064)
			(end 0.7874 0.4064)
			(stroke
				(width 0.1524)
				(type default)
			)
			(layer "F.SilkS")
		)
		(fp_line
			(start -0.67945 0.3048)
			(end -0.67945 -0.305054)
			(stroke
				(width 0.1)
				(type default)
			)
			(layer "F.Fab")
		)
		(fp_line
			(start -0.12065 0.3048)
			(end -0.67945 0.3048)
			(stroke
				(width 0.1)
				(type default)
			)
			(layer "F.Fab")
		)
		(fp_line
			(start 0.120396 0.3048)
			(end 0.120396 0.2794)
			(stroke
				(width 0.1)
				(type default)
			)
			(layer "F.Fab")
		)
		(fp_line
			(start 0.67945 0.3048)
			(end 0.120396 0.3048)
			(stroke
				(width 0.1)
				(type default)
			)
			(layer "F.Fab")
		)
		(fp_line
			(start -0.12065 0.2794)
			(end -0.12065 0.3048)
			(stroke
				(width 0.1)
				(type default)
			)
			(layer "F.Fab")
		)
		(fp_line
			(start 0.120396 0.2794)
			(end -0.12065 0.2794)
			(stroke
				(width 0.1)
				(type default)
			)
			(layer "F.Fab")
		)
		(fp_line
			(start -0.12065 -0.2794)
			(end 0.12065 -0.2794)
			(stroke
				(width 0.1)
				(type default)
			)
			(layer "F.Fab")
		)
		(fp_line
			(start 0.12065 -0.2794)
			(end 0.12065 -0.3048)
			(stroke
				(width 0.1)
				(type default)
			)
			(layer "F.Fab")
		)
		(fp_line
			(start 0.12065 -0.3048)
			(end 0.67945 -0.3048)
			(stroke
				(width 0.1)
				(type default)
			)
			(layer "F.Fab")
		)
		(fp_line
			(start 0.67945 -0.3048)
			(end 0.67945 0.3048)
			(stroke
				(width 0.1)
				(type default)
			)
			(layer "F.Fab")
		)
		(fp_line
			(start -0.67945 -0.305054)
			(end -0.12065 -0.305054)
			(stroke
				(width 0.1)
				(type default)
			)
			(layer "F.Fab")
		)
		(fp_line
			(start -0.12065 -0.305054)
			(end -0.12065 -0.2794)
			(stroke
				(width 0.1)
				(type default)
			)
			(layer "F.Fab")
		)
		(pad "1" smd circle
			(at -0.40005 0 270)
			(size 0 0)
			(layers "F.Cu" "F.Mask" "F.Paste")
			(net "P12V_PEX_P1V8_VIN_P")
		)
		(pad "2" smd circle
			(at 0.40005 0 270)
			(size 0 0)
			(layers "F.Cu" "F.Mask" "F.Paste")
			(net "P12V_PEX_P1V8_VIN_N")
		)
	)
	(footprint ""
		(layer "F.Cu")
		(at 24.342344 -250.070874 -90)
		(property "Reference" "R1161"
			(at 0 0 270)
			(layer "F.SilkS")
			(hide yes)
			(effects
				(font
					(size 1.27 1.27)
				)
			)
		)
		(property "Value" ""
			(at 0 0 270)
			(layer "F.Fab")
			(effects
				(font
					(size 1.27 1.27)
				)
			)
		)
		(duplicate_pad_numbers_are_jumpers no)
		(fp_line
			(start -0.7874 0.4064)
			(end -0.7874 -0.4064)
			(stroke
				(width 0.1524)
				(type default)
			)
			(layer "F.SilkS")
		)
		(fp_line
			(start 0.7874 0.4064)
			(end -0.7874 0.4064)
			(stroke
				(width 0.1524)
				(type default)
			)
			(layer "F.SilkS")
		)
		(fp_line
			(start -0.7874 -0.4064)
			(end 0.7874 -0.4064)
			(stroke
				(width 0.1524)
				(type default)
			)
			(layer "F.SilkS")
		)
		(fp_line
			(start 0.7874 -0.4064)
			(end 0.7874 0.4064)
			(stroke
				(width 0.1524)
				(type default)
			)
			(layer "F.SilkS")
		)
		(fp_line
			(start -0.67945 0.3048)
			(end -0.67945 -0.305054)
			(stroke
				(width 0.1)
				(type default)
			)
			(layer "F.Fab")
		)
		(fp_line
			(start -0.12065 0.3048)
			(end -0.67945 0.3048)
			(stroke
				(width 0.1)
				(type default)
			)
			(layer "F.Fab")
		)
		(fp_line
			(start 0.120396 0.3048)
			(end 0.120396 0.2794)
			(stroke
				(width 0.1)
				(type default)
			)
			(layer "F.Fab")
		)
		(fp_line
			(start 0.67945 0.3048)
			(end 0.120396 0.3048)
			(stroke
				(width 0.1)
				(type default)
			)
			(layer "F.Fab")
		)
		(fp_line
			(start -0.12065 0.2794)
			(end -0.12065 0.3048)
			(stroke
				(width 0.1)
				(type default)
			)
			(layer "F.Fab")
		)
		(fp_line
			(start 0.120396 0.2794)
			(end -0.12065 0.2794)
			(stroke
				(width 0.1)
				(type default)
			)
			(layer "F.Fab")
		)
		(fp_line
			(start -0.12065 -0.2794)
			(end 0.12065 -0.2794)
			(stroke
				(width 0.1)
				(type default)
			)
			(layer "F.Fab")
		)
		(fp_line
			(start 0.12065 -0.2794)
			(end 0.12065 -0.3048)
			(stroke
				(width 0.1)
				(type default)
			)
			(layer "F.Fab")
		)
		(fp_line
			(start 0.12065 -0.3048)
			(end 0.67945 -0.3048)
			(stroke
				(width 0.1)
				(type default)
			)
			(layer "F.Fab")
		)
		(fp_line
			(start 0.67945 -0.3048)
			(end 0.67945 0.3048)
			(stroke
				(width 0.1)
				(type default)
			)
			(layer "F.Fab")
		)
		(fp_line
			(start -0.67945 -0.305054)
			(end -0.12065 -0.305054)
			(stroke
				(width 0.1)
				(type default)
			)
			(layer "F.Fab")
		)
		(fp_line
			(start -0.12065 -0.305054)
			(end -0.12065 -0.2794)
			(stroke
				(width 0.1)
				(type default)
			)
			(layer "F.Fab")
		)
		(pad "1" smd circle
			(at -0.40005 0 270)
			(size 0 0)
			(layers "F.Cu" "F.Mask" "F.Paste")
			(net "PEX0_MODE_SEL9")
		)
		(pad "2" smd circle
			(at 0.40005 0 270)
			(size 0 0)
			(layers "F.Cu" "F.Mask" "F.Paste")
			(net "P1V8_PEX")
		)
	)
	(footprint ""
		(layer "F.Cu")
		(at 72.43445 -30.94609 180)
		(property "Reference" "C85"
			(at 0 0 180)
			(layer "F.SilkS")
			(hide yes)
			(effects
				(font
					(size 1.27 1.27)
				)
			)
		)
		(property "Value" ""
			(at 0 0 180)
			(layer "F.Fab")
			(effects
				(font
					(size 1.27 1.27)
				)
			)
		)
		(duplicate_pad_numbers_are_jumpers no)
		(fp_line
			(start 0.299974 0.150114)
			(end -0.299974 0.150114)
			(stroke
				(width 0.1)
				(type default)
			)
			(layer "F.Fab")
		)
		(fp_line
			(start 0.299974 -0.150114)
			(end 0.299974 0.150114)
			(stroke
				(width 0.1)
				(type default)
			)
			(layer "F.Fab")
		)
		(fp_line
			(start -0.299974 0.150114)
			(end -0.299974 -0.150114)
			(stroke
				(width 0.1)
				(type default)
			)
			(layer "F.Fab")
		)
		(fp_line
			(start -0.299974 -0.150114)
			(end 0.299974 -0.150114)
			(stroke
				(width 0.1)
				(type default)
			)
			(layer "F.Fab")
		)
		(pad "1" smd rect
			(at -0.2667 0 180)
			(size 0.3048 0.381)
			(layers "F.Cu" "F.Mask" "F.Paste")
			(net "P5E_PEX0_STN2_TX_DP<37>")
		)
		(pad "2" smd rect
			(at 0.2667 0 180)
			(size 0.3048 0.381)
			(layers "F.Cu" "F.Mask" "F.Paste")
			(net "P5E_PEX0_STN2_TX_C_DP<37>")
		)
	)
)
